(kicad_pcb
	(version 20260206)
	(generator "pcbnew")
	(generator_version "10.0")
	(general
		(thickness 1.6)
		(legacy_teardrops no)
	)
	(paper "A4")
	(title_block
		(title "v1-chassis-manager — T6M_CM_d_v01_1031_1645.brd")
		(comment 1 "Open CloudServer (Microsoft) / footprints 2323-2332 of 2512")
	)
	(layers
		(0 "F.Cu" signal "TOP")
		(4 "In1.Cu" signal "GND1")
		(6 "In2.Cu" signal "IN1")
		(8 "In3.Cu" signal "VCC1")
		(10 "In4.Cu" signal "VCC2")
		(12 "In5.Cu" signal "GND2")
		(14 "In6.Cu" signal "IN2")
		(16 "In7.Cu" signal "IN3")
		(18 "In8.Cu" signal "GND3")
		(2 "B.Cu" signal "BOTTOM")
		(9 "F.Adhes" user "F.Adhesive")
		(11 "B.Adhes" user "B.Adhesive")
		(13 "F.Paste" user "Package Geometry/Pastemask Top")
		(15 "B.Paste" user "Package Geometry/Pastemask Bottom")
		(5 "F.SilkS" user "Ref Des/Silkscreen Top")
		(7 "B.SilkS" user "Ref Des/Silkscreen Bottom")
		(1 "F.Mask" user "Board Geometry/Soldermask Top")
		(3 "B.Mask" user "Board Geometry/Soldermask Bottom")
		(17 "Dwgs.User" user "User.Drawings")
		(19 "Cmts.User" user "User.Comments")
		(21 "Eco1.User" user "User.Eco1")
		(23 "Eco2.User" user "User.Eco2")
		(25 "Edge.Cuts" user "Board Geometry/Outline")
		(27 "Margin" user)
		(31 "F.CrtYd" user "Package Geometry/Place Bound Top")
		(29 "B.CrtYd" user "Package Geometry/Place Bound Bottom")
		(35 "F.Fab" user "Ref Des/Assembly Top")
		(33 "B.Fab" user "Ref Des/Assembly Bottom")
	)
	(footprint ""
		(layer "B.Cu")
		(at 171.180252 -102.05339)
		(property "Reference" "C373"
			(at 7.670038 0.26543 0)
			(unlocked yes)
			(layer "B.SilkS")
			(effects
				(font
					(size 0.7874 0.5842)
					(thickness 0.1524)
				)
				(justify left mirror)
			)
		)
		(property "Value" ""
			(at 0 0 0)
			(layer "B.Fab")
			(effects
				(font
					(size 1.27 1.27)
				)
				(justify mirror)
			)
		)
		(duplicate_pad_numbers_are_jumpers no)
		(fp_line
			(start -0.7874 -0.4064)
			(end -0.7874 0.4064)
			(stroke
				(width 0.1524)
				(type default)
			)
			(layer "B.SilkS")
		)
		(fp_line
			(start -0.7874 0.4064)
			(end 0.7874 0.4064)
			(stroke
				(width 0.1524)
				(type default)
			)
			(layer "B.SilkS")
		)
		(fp_line
			(start 0 0.381)
			(end 0 -0.381)
			(stroke
				(width 0.1524)
				(type default)
			)
			(layer "B.SilkS")
		)
		(fp_line
			(start 0.7874 -0.4064)
			(end -0.7874 -0.4064)
			(stroke
				(width 0.1524)
				(type default)
			)
			(layer "B.SilkS")
		)
		(fp_line
			(start 0.7874 0.4064)
			(end 0.7874 -0.4064)
			(stroke
				(width 0.1524)
				(type default)
			)
			(layer "B.SilkS")
		)
		(fp_poly
			(pts
				(xy 0.5334 0.254) (xy 0.635 0.254) (xy 0.635 0.2286) (xy 0.635 -0.254) (xy 0.5334 -0.254) (xy 0.5334 -0.2794)
				(xy -0.5334 -0.2794) (xy -0.5334 -0.254) (xy -0.635 -0.254) (xy -0.635 0.254) (xy -0.5334 0.254)
				(xy -0.5334 0.2794) (xy 0.508 0.2794) (xy 0.5334 0.2794)
			)
			(stroke
				(width 0)
				(type default)
			)
			(fill no)
			(layer "B.CrtYd")
		)
		(pad "1" smd rect
			(at -0.40005 0 180)
			(size 0.4572 0.508)
			(layers "B.Cu" "B.Mask" "B.Paste")
			(net "GND")
		)
		(pad "2" smd rect
			(at 0.40005 0 180)
			(size 0.4572 0.508)
			(layers "B.Cu" "B.Mask" "B.Paste")
			(net "P1V05_NODE1")
		)
	)
	(footprint ""
		(layer "B.Cu")
		(at 62.09792 -69.164454 90)
		(property "Reference" "C131"
			(at -34.018982 -14.26845 270)
			(unlocked yes)
			(layer "B.SilkS")
			(effects
				(font
					(size 0.7874 0.5842)
					(thickness 0.1524)
				)
				(justify left mirror)
			)
		)
		(property "Value" ""
			(at 0 0 90)
			(layer "B.Fab")
			(effects
				(font
					(size 1.27 1.27)
				)
				(justify mirror)
			)
		)
		(duplicate_pad_numbers_are_jumpers no)
		(fp_line
			(start 0.7874 -0.4064)
			(end -0.7874 -0.4064)
			(stroke
				(width 0.1524)
				(type default)
			)
			(layer "B.SilkS")
		)
		(fp_line
			(start -0.7874 -0.4064)
			(end -0.7874 0.4064)
			(stroke
				(width 0.1524)
				(type default)
			)
			(layer "B.SilkS")
		)
		(fp_line
			(start 0 0.381)
			(end 0 -0.381)
			(stroke
				(width 0.1524)
				(type default)
			)
			(layer "B.SilkS")
		)
		(fp_line
			(start 0.7874 0.4064)
			(end 0.7874 -0.4064)
			(stroke
				(width 0.1524)
				(type default)
			)
			(layer "B.SilkS")
		)
		(fp_line
			(start -0.7874 0.4064)
			(end 0.7874 0.4064)
			(stroke
				(width 0.1524)
				(type default)
			)
			(layer "B.SilkS")
		)
		(fp_poly
			(pts
				(xy 0.5334 0.254) (xy 0.635 0.254) (xy 0.635 0.2286) (xy 0.635 -0.254) (xy 0.5334 -0.254) (xy 0.5334 -0.2794)
				(xy -0.5334 -0.2794) (xy -0.5334 -0.254) (xy -0.635 -0.254) (xy -0.635 0.254) (xy -0.5334 0.254)
				(xy -0.5334 0.2794) (xy 0.508 0.2794) (xy 0.5334 0.2794)
			)
			(stroke
				(width 0)
				(type default)
			)
			(fill no)
			(layer "B.CrtYd")
		)
		(pad "1" smd rect
			(at -0.40005 0 270)
			(size 0.4572 0.508)
			(layers "B.Cu" "B.Mask" "B.Paste")
			(net "PV_VDDR_VCCCLK_DDR3_NODE1")
		)
		(pad "2" smd rect
			(at 0.40005 0 270)
			(size 0.4572 0.508)
			(layers "B.Cu" "B.Mask" "B.Paste")
			(net "GND")
		)
	)
	(footprint ""
		(layer "B.Cu")
		(at 142.07236 -178.093624 180)
		(property "Reference" "R740"
			(at 0.467868 1.204722 0)
			(unlocked yes)
			(layer "B.SilkS")
			(effects
				(font
					(size 0.7874 0.5842)
					(thickness 0.1524)
				)
				(justify left mirror)
			)
		)
		(property "Value" ""
			(at 0 0 0)
			(layer "B.Fab")
			(effects
				(font
					(size 1.27 1.27)
				)
				(justify mirror)
			)
		)
		(duplicate_pad_numbers_are_jumpers no)
		(fp_line
			(start 0.7874 0.4064)
			(end 0.7874 -0.4064)
			(stroke
				(width 0.1524)
				(type default)
			)
			(layer "B.SilkS")
		)
		(fp_line
			(start 0.7874 -0.4064)
			(end -0.7874 -0.4064)
			(stroke
				(width 0.1524)
				(type default)
			)
			(layer "B.SilkS")
		)
		(fp_line
			(start -0.7874 0.4064)
			(end 0.7874 0.4064)
			(stroke
				(width 0.1524)
				(type default)
			)
			(layer "B.SilkS")
		)
		(fp_line
			(start -0.7874 -0.4064)
			(end -0.7874 0.4064)
			(stroke
				(width 0.1524)
				(type default)
			)
			(layer "B.SilkS")
		)
		(fp_poly
			(pts
				(xy 0.508 0.2794) (xy 0.508 0.2286) (xy 0.635 0.2286) (xy 0.635 -0.254) (xy 0.5334 -0.254) (xy 0.5334 -0.2794)
				(xy -0.5334 -0.2794) (xy -0.5334 -0.254) (xy -0.635 -0.254) (xy -0.635 0.254) (xy -0.5334 0.254)
				(xy -0.5334 0.2794)
			)
			(stroke
				(width 0)
				(type default)
			)
			(fill no)
			(layer "B.CrtYd")
		)
		(pad "1" smd rect
			(at -0.40005 0)
			(size 0.4572 0.508)
			(layers "B.Cu" "B.Mask" "B.Paste")
			(net "T10_NODE4_EN")
		)
		(pad "2" smd rect
			(at 0.40005 0)
			(size 0.4572 0.508)
			(layers "B.Cu" "B.Mask" "B.Paste")
			(net "P5V_NODE1")
		)
	)
	(footprint ""
		(layer "B.Cu")
		(at 47.424086 -129.883662 180)
		(property "Reference" "C235"
			(at -3.865372 -0.06858 0)
			(unlocked yes)
			(layer "B.SilkS")
			(effects
				(font
					(size 0.7874 0.5842)
					(thickness 0.1524)
				)
				(justify left mirror)
			)
		)
		(property "Value" ""
			(at 0 0 0)
			(layer "B.Fab")
			(effects
				(font
					(size 1.27 1.27)
				)
				(justify mirror)
			)
		)
		(duplicate_pad_numbers_are_jumpers no)
		(fp_line
			(start 0.7874 0.4064)
			(end 0.7874 -0.4064)
			(stroke
				(width 0.1524)
				(type default)
			)
			(layer "B.SilkS")
		)
		(fp_line
			(start 0.7874 -0.4064)
			(end -0.7874 -0.4064)
			(stroke
				(width 0.1524)
				(type default)
			)
			(layer "B.SilkS")
		)
		(fp_line
			(start 0 0.381)
			(end 0 -0.381)
			(stroke
				(width 0.1524)
				(type default)
			)
			(layer "B.SilkS")
		)
		(fp_line
			(start -0.7874 0.4064)
			(end 0.7874 0.4064)
			(stroke
				(width 0.1524)
				(type default)
			)
			(layer "B.SilkS")
		)
		(fp_line
			(start -0.7874 -0.4064)
			(end -0.7874 0.4064)
			(stroke
				(width 0.1524)
				(type default)
			)
			(layer "B.SilkS")
		)
		(fp_poly
			(pts
				(xy 0.5334 0.254) (xy 0.635 0.254) (xy 0.635 0.2286) (xy 0.635 -0.254) (xy 0.5334 -0.254) (xy 0.5334 -0.2794)
				(xy -0.5334 -0.2794) (xy -0.5334 -0.254) (xy -0.635 -0.254) (xy -0.635 0.254) (xy -0.5334 0.254)
				(xy -0.5334 0.2794) (xy 0.508 0.2794) (xy 0.5334 0.2794)
			)
			(stroke
				(width 0)
				(type default)
			)
			(fill no)
			(layer "B.CrtYd")
		)
		(pad "1" smd rect
			(at -0.40005 0)
			(size 0.4572 0.508)
			(layers "B.Cu" "B.Mask" "B.Paste")
			(net "P1V538_BMC_NODE1")
		)
		(pad "2" smd rect
			(at 0.40005 0)
			(size 0.4572 0.508)
			(layers "B.Cu" "B.Mask" "B.Paste")
			(net "GND")
		)
	)
	(footprint ""
		(layer "B.Cu")
		(at 44.718732 -94.40037 -90)
		(property "Reference" "C31"
			(at 4.703318 4.488434 270)
			(unlocked yes)
			(layer "B.SilkS")
			(effects
				(font
					(size 0.7874 0.5842)
					(thickness 0.1524)
				)
				(justify left mirror)
			)
		)
		(property "Value" ""
			(at 0 0 90)
			(layer "B.Fab")
			(effects
				(font
					(size 1.27 1.27)
				)
				(justify mirror)
			)
		)
		(duplicate_pad_numbers_are_jumpers no)
		(fp_line
			(start -0.7874 0.4064)
			(end 0.7874 0.4064)
			(stroke
				(width 0.1524)
				(type default)
			)
			(layer "B.SilkS")
		)
		(fp_line
			(start 0.7874 0.4064)
			(end 0.7874 -0.4064)
			(stroke
				(width 0.1524)
				(type default)
			)
			(layer "B.SilkS")
		)
		(fp_line
			(start 0 0.381)
			(end 0 -0.381)
			(stroke
				(width 0.1524)
				(type default)
			)
			(layer "B.SilkS")
		)
		(fp_line
			(start -0.7874 -0.4064)
			(end -0.7874 0.4064)
			(stroke
				(width 0.1524)
				(type default)
			)
			(layer "B.SilkS")
		)
		(fp_line
			(start 0.7874 -0.4064)
			(end -0.7874 -0.4064)
			(stroke
				(width 0.1524)
				(type default)
			)
			(layer "B.SilkS")
		)
		(fp_poly
			(pts
				(xy 0.5334 0.254) (xy 0.635 0.254) (xy 0.635 0.2286) (xy 0.635 -0.254) (xy 0.5334 -0.254) (xy 0.5334 -0.2794)
				(xy -0.5334 -0.2794) (xy -0.5334 -0.254) (xy -0.635 -0.254) (xy -0.635 0.254) (xy -0.5334 0.254)
				(xy -0.5334 0.2794) (xy 0.508 0.2794) (xy 0.5334 0.2794)
			)
			(stroke
				(width 0)
				(type default)
			)
			(fill no)
			(layer "B.CrtYd")
		)
		(pad "1" smd rect
			(at -0.40005 0 90)
			(size 0.4572 0.508)
			(layers "B.Cu" "B.Mask" "B.Paste")
			(net "GND")
		)
		(pad "2" smd rect
			(at 0.40005 0 90)
			(size 0.4572 0.508)
			(layers "B.Cu" "B.Mask" "B.Paste")
			(net "SMB_CPU_NODE1_BMC_DAT_RR")
		)
	)
	(footprint ""
		(layer "B.Cu")
		(at 37.645086 -139.789662)
		(property "Reference" "C224"
			(at -2.11328 0.263906 0)
			(unlocked yes)
			(layer "B.SilkS")
			(effects
				(font
					(size 0.7874 0.5842)
					(thickness 0.1524)
				)
				(justify left mirror)
			)
		)
		(property "Value" ""
			(at 0 0 0)
			(layer "B.Fab")
			(effects
				(font
					(size 1.27 1.27)
				)
				(justify mirror)
			)
		)
		(duplicate_pad_numbers_are_jumpers no)
		(fp_line
			(start -0.7874 -0.4064)
			(end -0.7874 0.4064)
			(stroke
				(width 0.1524)
				(type default)
			)
			(layer "B.SilkS")
		)
		(fp_line
			(start -0.7874 0.4064)
			(end 0.7874 0.4064)
			(stroke
				(width 0.1524)
				(type default)
			)
			(layer "B.SilkS")
		)
		(fp_line
			(start 0 0.381)
			(end 0 -0.381)
			(stroke
				(width 0.1524)
				(type default)
			)
			(layer "B.SilkS")
		)
		(fp_line
			(start 0.7874 -0.4064)
			(end -0.7874 -0.4064)
			(stroke
				(width 0.1524)
				(type default)
			)
			(layer "B.SilkS")
		)
		(fp_line
			(start 0.7874 0.4064)
			(end 0.7874 -0.4064)
			(stroke
				(width 0.1524)
				(type default)
			)
			(layer "B.SilkS")
		)
		(fp_poly
			(pts
				(xy 0.5334 0.254) (xy 0.635 0.254) (xy 0.635 0.2286) (xy 0.635 -0.254) (xy 0.5334 -0.254) (xy 0.5334 -0.2794)
				(xy -0.5334 -0.2794) (xy -0.5334 -0.254) (xy -0.635 -0.254) (xy -0.635 0.254) (xy -0.5334 0.254)
				(xy -0.5334 0.2794) (xy 0.508 0.2794) (xy 0.5334 0.2794)
			)
			(stroke
				(width 0)
				(type default)
			)
			(fill no)
			(layer "B.CrtYd")
		)
		(pad "1" smd rect
			(at -0.40005 0 180)
			(size 0.4572 0.508)
			(layers "B.Cu" "B.Mask" "B.Paste")
			(net "P0V75_BMC_VTTREF_NODE1")
		)
		(pad "2" smd rect
			(at 0.40005 0 180)
			(size 0.4572 0.508)
			(layers "B.Cu" "B.Mask" "B.Paste")
			(net "GND")
		)
	)
	(footprint ""
		(layer "B.Cu")
		(at 129.143252 -123.7488 90)
		(property "Reference" "C9"
			(at -0.178054 1.089152 270)
			(unlocked yes)
			(layer "B.SilkS")
			(effects
				(font
					(size 0.7874 0.5842)
					(thickness 0.1524)
				)
				(justify mirror)
			)
		)
		(property "Value" ""
			(at 0 0 90)
			(layer "B.Fab")
			(effects
				(font
					(size 1.27 1.27)
				)
				(justify mirror)
			)
		)
		(duplicate_pad_numbers_are_jumpers no)
		(fp_line
			(start 1.2954 -0.5842)
			(end -1.2954 -0.5842)
			(stroke
				(width 0.1524)
				(type default)
			)
			(layer "B.SilkS")
		)
		(fp_line
			(start 0 -0.5842)
			(end 0 0.5842)
			(stroke
				(width 0.1524)
				(type default)
			)
			(layer "B.SilkS")
		)
		(fp_line
			(start -1.2954 -0.5842)
			(end -1.2954 0.5842)
			(stroke
				(width 0.1524)
				(type default)
			)
			(layer "B.SilkS")
		)
		(fp_line
			(start 1.2954 0.5842)
			(end 1.2954 -0.5842)
			(stroke
				(width 0.1524)
				(type default)
			)
			(layer "B.SilkS")
		)
		(fp_line
			(start -1.2954 0.5842)
			(end 1.2954 0.5842)
			(stroke
				(width 0.1524)
				(type default)
			)
			(layer "B.SilkS")
		)
		(fp_poly
			(pts
				(xy -0.8636 -0.4572) (xy -0.8636 -0.3556) (xy -1.143 -0.3556) (xy -1.143 0.3556) (xy -0.8636 0.3556)
				(xy -0.8636 0.4572) (xy 0.8636 0.4572) (xy 0.8636 0.3556) (xy 1.143 0.3556) (xy 1.143 -0.3556) (xy 0.8636 -0.3556)
				(xy 0.8636 -0.4572)
			)
			(stroke
				(width 0)
				(type default)
			)
			(fill no)
			(layer "B.CrtYd")
		)
		(fp_line
			(start 0.884936 -0.504952)
			(end -0.884936 -0.504952)
			(stroke
				(width 0.1)
				(type default)
			)
			(layer "B.Fab")
		)
		(fp_line
			(start -0.884936 -0.504952)
			(end -0.884936 0.504952)
			(stroke
				(width 0.1)
				(type default)
			)
			(layer "B.Fab")
		)
		(fp_line
			(start 0.884936 0.504952)
			(end 0.884936 -0.504952)
			(stroke
				(width 0.1)
				(type default)
			)
			(layer "B.Fab")
		)
		(fp_line
			(start -0.884936 0.504952)
			(end 0.884936 0.504952)
			(stroke
				(width 0.1)
				(type default)
			)
			(layer "B.Fab")
		)
		(pad "1" smd rect
			(at -0.7366 0 180)
			(size 0.7112 0.8128)
			(layers "B.Cu" "B.Mask" "B.Paste")
			(net "P1V05_CLK_NODE1")
		)
		(pad "2" smd rect
			(at 0.7366 0 180)
			(size 0.7112 0.8128)
			(layers "B.Cu" "B.Mask" "B.Paste")
			(net "GND")
		)
	)
	(footprint ""
		(layer "B.Cu")
		(at 153.90876 -187.872624 -90)
		(property "Reference" "C651"
			(at -4.565396 3.533902 270)
			(unlocked yes)
			(layer "B.SilkS")
			(effects
				(font
					(size 0.7874 0.5842)
					(thickness 0.1524)
				)
				(justify left mirror)
			)
		)
		(property "Value" ""
			(at 0 0 90)
			(layer "B.Fab")
			(effects
				(font
					(size 1.27 1.27)
				)
				(justify mirror)
			)
		)
		(duplicate_pad_numbers_are_jumpers no)
		(fp_line
			(start -0.7874 0.4064)
			(end 0.7874 0.4064)
			(stroke
				(width 0.1524)
				(type default)
			)
			(layer "B.SilkS")
		)
		(fp_line
			(start 0.7874 0.4064)
			(end 0.7874 -0.4064)
			(stroke
				(width 0.1524)
				(type default)
			)
			(layer "B.SilkS")
		)
		(fp_line
			(start 0 0.381)
			(end 0 -0.381)
			(stroke
				(width 0.1524)
				(type default)
			)
			(layer "B.SilkS")
		)
		(fp_line
			(start -0.7874 -0.4064)
			(end -0.7874 0.4064)
			(stroke
				(width 0.1524)
				(type default)
			)
			(layer "B.SilkS")
		)
		(fp_line
			(start 0.7874 -0.4064)
			(end -0.7874 -0.4064)
			(stroke
				(width 0.1524)
				(type default)
			)
			(layer "B.SilkS")
		)
		(fp_poly
			(pts
				(xy 0.5334 0.254) (xy 0.635 0.254) (xy 0.635 0.2286) (xy 0.635 -0.254) (xy 0.5334 -0.254) (xy 0.5334 -0.2794)
				(xy -0.5334 -0.2794) (xy -0.5334 -0.254) (xy -0.635 -0.254) (xy -0.635 0.254) (xy -0.5334 0.254)
				(xy -0.5334 0.2794) (xy 0.508 0.2794) (xy 0.5334 0.2794)
			)
			(stroke
				(width 0)
				(type default)
			)
			(fill no)
			(layer "B.CrtYd")
		)
		(pad "1" smd rect
			(at -0.40005 0 90)
			(size 0.4572 0.508)
			(layers "B.Cu" "B.Mask" "B.Paste")
			(net "T11_NODE2_EN_R")
		)
		(pad "2" smd rect
			(at 0.40005 0 90)
			(size 0.4572 0.508)
			(layers "B.Cu" "B.Mask" "B.Paste")
			(net "GND")
		)
	)
	(footprint ""
		(layer "B.Cu")
		(at 57.070498 -96.696784 90)
		(property "Reference" "R140"
			(at 6.405118 -4.364228 270)
			(unlocked yes)
			(layer "B.SilkS")
			(effects
				(font
					(size 0.7874 0.5842)
					(thickness 0.1524)
				)
				(justify left mirror)
			)
		)
		(property "Value" ""
			(at 0 0 90)
			(layer "B.Fab")
			(effects
				(font
					(size 1.27 1.27)
				)
				(justify mirror)
			)
		)
		(duplicate_pad_numbers_are_jumpers no)
		(fp_line
			(start 0.7874 -0.4064)
			(end -0.7874 -0.4064)
			(stroke
				(width 0.1524)
				(type default)
			)
			(layer "B.SilkS")
		)
		(fp_line
			(start -0.7874 -0.4064)
			(end -0.7874 0.4064)
			(stroke
				(width 0.1524)
				(type default)
			)
			(layer "B.SilkS")
		)
		(fp_line
			(start 0.7874 0.4064)
			(end 0.7874 -0.4064)
			(stroke
				(width 0.1524)
				(type default)
			)
			(layer "B.SilkS")
		)
		(fp_line
			(start -0.7874 0.4064)
			(end 0.7874 0.4064)
			(stroke
				(width 0.1524)
				(type default)
			)
			(layer "B.SilkS")
		)
		(fp_poly
			(pts
				(xy 0.508 0.2794) (xy 0.508 0.2286) (xy 0.635 0.2286) (xy 0.635 -0.254) (xy 0.5334 -0.254) (xy 0.5334 -0.2794)
				(xy -0.5334 -0.2794) (xy -0.5334 -0.254) (xy -0.635 -0.254) (xy -0.635 0.254) (xy -0.5334 0.254)
				(xy -0.5334 0.2794)
			)
			(stroke
				(width 0)
				(type default)
			)
			(fill no)
			(layer "B.CrtYd")
		)
		(pad "1" smd rect
			(at -0.40005 0 270)
			(size 0.4572 0.508)
			(layers "B.Cu" "B.Mask" "B.Paste")
			(net "H_CPU_NODE1_THRM_LS_L")
		)
		(pad "2" smd rect
			(at 0.40005 0 270)
			(size 0.4572 0.508)
			(layers "B.Cu" "B.Mask" "B.Paste")
			(net "P3V3_NODE1")
		)
	)
	(footprint ""
		(layer "B.Cu")
		(at 161.458148 -196.09943)
		(property "Reference" "TP12"
			(at 0 0 0)
			(layer "B.SilkS")
			(hide yes)
			(effects
				(font
					(size 1.27 1.27)
				)
				(justify mirror)
			)
		)
		(property "Value" ""
			(at 0 0 0)
			(layer "B.Fab")
			(effects
				(font
					(size 1.27 1.27)
				)
				(justify mirror)
			)
		)
		(duplicate_pad_numbers_are_jumpers no)
		(fp_poly
			(pts
				(arc
					(start 0 -0.381)
					(mid 0 0.381)
					(end 0 -0.381)
				)
			)
			(stroke
				(width 0)
				(type default)
			)
			(fill no)
			(layer "B.CrtYd")
		)
		(pad "1" smd circle
			(at 0 0 180)
			(size 0.762 0.762)
			(layers "B.Cu" "B.Mask" "B.Paste")
			(net "UART_CTS_RP6_L")
		)
	)
)
